BOARD : G:\<user>\F0T\9052_F0T_PDB_Converter_Brick_F\Board\TO\9052_F0T_PDB_Converter_Brick_F_V03_1208_1600.brd
Unit  : mil & mm
Date  : Dec 12 13:12:53 2022

-----------------------------------------------------------------------------
Total Test points with distance < 39 mils = 0 within 0 pairs
-----------------------------------------------------------------------------
Total Test points with distance 39=< tp <50 mils = 0 within 0 pairs
-----------------------------------------------------------------------------
50=<x<75:  (1) P12V_HPDB_0_EN_R                    1782.65    2134.43 BOTTOM
           (2) P12V_HPDB_0_TIMER                   1759.76    2187.75 BOTTOM
50=<x<75:  (1) P12V_HPDB_PWRGD                     1660.68    2387.49 BOTTOM
           (2) P12V_HPDB_0_FB                      1600.17    2377.64 BOTTOM
50=<x<75:  (1) P12V_HPDB_0_SS                      1738.69    2281.68 BOTTOM
           (2) P12V_HPDB_0_ISET                    1783.29    2329.00 BOTTOM
50=<x<75:  (1) SMB_P52V_VPDB_SCL_R                 7530.20    3385.00 BOTTOM
           (2) PU_9543_1_INT1                      7535.50    3441.61 BOTTOM
50=<x<75:  (1) TP_9543_MISC_INT_N                  7590.00    3655.00 BOTTOM
           (2) SMB_HPDB_MISC_SCL                   7530.00    3665.00 BOTTOM
50=<x<75:  (1) TP_9543_MISC_INT_N                  7590.00    3655.00 BOTTOM
           (2) SMB_HPDB_MISC_SDA                   7662.40    3664.46 BOTTOM
50=<x<75:  (1) SMB_VPDB_IOEXP_SDA                  8155.00    2815.00 BOTTOM
           (2) PRSNT_HPDB_N                        8110.00    2860.00 BOTTOM
50=<x<75:  (1) P52V_HS1_DVCC                      10439.36    1457.45 BOTTOM
           (2) P52V_HS1_ADR1                      10493.56    1439.00 BOTTOM
50=<x<75:  (1) P52V_HS_4287_S1P                   10190.40    1573.10 BOTTOM
           (2) P52V_HS_4287_ADC_N                 10221.68    1617.83 BOTTOM
50=<x<75:  (1) P52V_HS_4287_S1P                   10190.40    1573.10 BOTTOM
           (2) P52V_HS_4287_S2P                   10179.09    1514.24 BOTTOM
50=<x<75:  (1) P52V_HS_4287_ADC_N                 10221.68    1617.83 BOTTOM
           (2) P52V_HS1_4287_GATE_R               10197.00    1666.00 BOTTOM
50=<x<75:  (1) GND_FIELD_SIGNAL                   10390.16    1890.75 BOTTOM
           (2) PWRGD_P52V_HS1_PG_N                10390.16    1830.27 BOTTOM
50=<x<75:  (1) P52V_HS1_4287_GATE2_R              10220.00    1712.00 BOTTOM
           (2) P52V_HS1_4287_GATE_R               10197.00    1666.00 BOTTOM
50=<x<75:  (1) P52V_HS1_ADR1                      10493.56    1439.00 BOTTOM
           (2) P52V_HS1_MODE                      10545.00    1485.00 BOTTOM
50=<x<75:  (1) P52V_HS1_ESTART                    10960.00    1705.00 BOTTOM
           (2) P52V_HS1_EFAULT                    10960.00    1650.00 BOTTOM
50=<x<75:  (1) P52V_HS1_GPO1                      11212.38    1445.00 BOTTOM
           (2) GND_FIELD_SIGNAL                   11205.24    1384.57 BOTTOM
50=<x<75:  (1) P52V_HS1_VCAP                      11080.00    1720.00 BOTTOM
           (2) P52V_HS1_ESTART_R                  11133.68    1716.19 BOTTOM
50=<x<75:  (1) P52V_HS1_ESTART_R                  11133.68    1716.19 BOTTOM
           (2) P52V_HS1_ADR0                      11131.29    1657.19 BOTTOM
50=<x<75:  (1) P52V_HS_4287_ADC_P                 11795.00    4767.50 BOTTOM
           (2) P52V_HS_1272_S_P                   11795.00    4697.50 BOTTOM
50=<x<75:  (1) SMB_P52V_HS1_SDAI                  10595.00    1755.00 TOP   
           (2) P52V_HS1_CS                        10660.00    1755.00 TOP   
50=<x<75:  (1) SMB_P52V_HS1_SDAI                  10595.00    1755.00 TOP   
           (2) SMB_P52V_VPDB_SCL_R3               10625.00    1810.00 TOP   
50=<x<75:  (1) P52V_HS1_CS                        10660.00    1755.00 TOP   
           (2) SMB_P52V_VPDB_SCL_R3               10625.00    1810.00 TOP   
50=<x<75:  (1) FM_HSC_EN_FUSE                     11155.00     975.00 TOP   
           (2) FM_HSC_EN_BUSBAR                   11210.00     945.00 TOP   
50=<x<75:  (1) P52V_HS1_GPO2                      11180.00    1460.00 TOP   
           (2) P52V_HS1_MCB                       11125.00    1510.00 TOP   
50=<x<75:  (1) SMB_CM_HS1_3V3SB_DATI              11065.00    1550.00 TOP   
           (2) P52V_HS1_MCB                       11125.00    1510.00 TOP   
50=<x<75:  (1) SMB_CM_HS1_3V3SB_DATI              11065.00    1550.00 TOP   
           (2) SMB_P52V_VPDB_SCL_R2               11055.00    1617.79 TOP   
50=<x<75:  (1) P52V_HS1_EFAULT_R                  11108.00    1700.00 TOP   
           (2) P52V_HS1_ISTART                    11085.00    1760.00 TOP   
50=<x<75:  (1) P52V_HS1_VREG                      11310.88    1869.12 TOP   
           (2) P52V_HS1_VCC                       11378.08    1875.88 TOP   
50=<x<75:  (1) P52V_HS1_ISTART                    11085.00    1760.00 TOP   
           (2) P52V_HS1_ISET                      11051.70    1826.30 TOP   
Total Test points with distance 50=< tp <75 mils = 46 within 29 pairs
-----------------------------------------------------------------------------
|--------------------------------------------------------------------------------------------------------------------|
|                                                      TESTPIN                                                       |
|--------------------------------------------------------------------------------------------------------------------|
|                  |                                 |       |            MIL            |            MM             |
|                  |                                 |       |---------------------------|---------------------------|
|     PADSTACK     |            NET NAME             | LAYER |      X      |      Y      |      X      |      Y      |
|--------------------------------------------------------------------------------------------------------------------|
 C123D83            GND                               BOTTOM        3362.99       2772.04        85.420        70.410 
 C123D83            GND                               BOTTOM        3512.99       2772.04        89.230        70.410 
 C123D83            GND                               BOTTOM        4937.80       2772.04       125.420        70.410 
 C123D83            GND                               BOTTOM        5087.80       2772.04       129.230        70.410 
 C123D83            P12V_BRICK                        BOTTOM        2538.19       2772.04        64.470        70.410 
 C123D83            P12V_BRICK                        BOTTOM        2688.19       2772.04        68.280        70.410 
 C123D83            P12V_BRICK                        BOTTOM        4112.99       2772.04       104.470        70.410 
 C123D83            P12V_BRICK                        BOTTOM        4262.99       2772.04       108.280        70.410 
 C123D83            P12V_BRICK                        BOTTOM        5687.80       2772.04       144.470        70.410 
 C123D83            P12V_BRICK                        BOTTOM        5837.80       2772.04       148.280        70.410 
 C50D34             FAN_PWR_EN_BUF                    BOTTOM         437.80       3347.24        11.120        85.020 
 C50D34             GPU_HSC_EN                        BOTTOM         437.80       3247.24        11.120        82.480 
 C50D34             P12V_HPDB                         BOTTOM         487.80       3497.24        12.390        88.830 
 C50D34             P12V_HPDB_PWRGD                   BOTTOM         437.80       3147.24        11.120        79.940 
 C50D34             SMB_HPDB_MISC_R_SCL               BOTTOM         387.80       3497.24         9.850        88.830 
 C50D34             SMB_P52V_HPDB_R_SDA               BOTTOM         337.80       3347.24         8.580        85.020 
 C52D36             BRICK0_PMBADD                     BOTTOM        5545.28       2672.04       140.850        67.870 
 C52D36             BRICK1_PMBADD                     BOTTOM        3970.47       2672.04       100.850        67.870 
 C52D36             BRICK2_PMBADD                     BOTTOM        7120.09       2672.04       180.850        67.870 
 C52D36             BRICK3_PMBADD                     BOTTOM        2395.67       2672.04        60.850        67.870 
 C52D36             P12V_BRICK0_PWRGD                 BOTTOM        5151.58       2672.04       130.850        67.870 
 C52D36             P12V_BRICK_PWRGD                  BOTTOM        2001.97       2672.04        50.850        67.870 
 C52D36             P12V_MB0_SENSE+                   BOTTOM        5624.02       2672.04       142.850        67.870 
 C52D36             P12V_MB0_SENSE-                   BOTTOM        5230.32       2672.04       132.850        67.870 
 C52D36             P12V_MB1_SENSE+                   BOTTOM        4049.21       2672.04       102.850        67.870 
 C52D36             P12V_MB1_SENSE-                   BOTTOM        3655.51       2672.04        92.850        67.870 
 C52D36             P12V_MB2_SENSE+                   BOTTOM        7198.83       2672.04       182.850        67.870 
 C52D36             P12V_MB2_SENSE-                   BOTTOM        6805.13       2672.04       172.850        67.870 
 C52D36             P12V_MB3_SENSE+                   BOTTOM        2474.41       2672.04        62.850        67.870 
 C52D36             P12V_MB3_SENSE-                   BOTTOM        2080.71       2672.04        52.850        67.870 
 C52D36             SMB_BRICK0_ALERT                  BOTTOM        5387.80       2672.04       136.850        67.870 
 C52D36             SMB_BRICK0_SCL                    BOTTOM        5466.54       2672.04       138.850        67.870 
 C52D36             SMB_BRICK0_SDA                    BOTTOM        5309.06       2672.04       134.850        67.870 
 C52D36             SMB_BRICK1_ALERT                  BOTTOM        3812.99       2672.04        96.850        67.870 
 C52D36             SMB_BRICK1_SCL                    BOTTOM        3891.73       2672.04        98.850        67.870 
 C52D36             SMB_BRICK1_SDA                    BOTTOM        3734.25       2672.04        94.850        67.870 
 C52D36             SMB_BRICK2_ALERT                  BOTTOM        6962.61       2672.04       176.850        67.870 
 C52D36             SMB_BRICK2_SCL                    BOTTOM        7041.35       2672.04       178.850        67.870 
 C52D36             SMB_BRICK2_SDA                    BOTTOM        6883.87       2672.04       174.850        67.870 
 C52D36             SMB_BRICK3_ALERT                  BOTTOM        2238.19       2672.04        56.850        67.870 
 C52D36             SMB_BRICK3_SCL                    BOTTOM        2316.93       2672.04        58.850        67.870 
 C52D36             SMB_BRICK3_SDA                    BOTTOM        2159.45       2672.04        54.850        67.870 
 C58D41             GND                               BOTTOM         487.80       2392.91        12.390        60.780 
 C58D41             GND                               BOTTOM         487.80       2592.91        12.390        65.860 
 C58D41             P52V_FAN                          BOTTOM         487.80       2792.91        12.390        70.940 
 C58D41             P52V_FAN                          BOTTOM         487.80       2992.91        12.390        76.020 
 C66D46             GND                               BOTTOM       10110.00       1080.00       256.794        27.432 
 C66D46             SMB_P52V_VPDB_DEBUG_SCL           BOTTOM       10110.00       1180.00       256.794        29.972 
 C93D63             BRICK_P12V0_ON_OFF_R              BOTTOM        5387.80       4772.04       136.850       121.210 
 C93D63             BRICK_P12V1_ON_OFF_R              BOTTOM        3812.99       4772.04        96.850       121.210 
 C93D63             BRICK_P12V2_ON_OFF_R              BOTTOM        6962.61       4772.04       176.850       121.210 
 C93D63             BRICK_P12V3_ON_OFF_R              BOTTOM        2238.19       4772.04        56.850       121.210 
 C93D63             GND                               BOTTOM        1938.19       4772.04        49.230       121.210 
 C93D63             GND                               BOTTOM        3512.99       4772.04        89.230       121.210 
 C93D63             GND                               BOTTOM        5087.80       4772.04       129.230       121.210 
 S66D46             SMB_P52V_VPDB_DEBUG_SDA           BOTTOM       10110.00        980.00       256.794        24.892 
 TP26B              BOARD_ID_0                        BOTTOM        8495.00       2815.00       215.773        71.501 
 TP26B              BOARD_ID_2                        BOTTOM        8414.09       2805.66       213.718        71.264 
 TP26B              BRICK_P12V0_EN_N                  BOTTOM        5445.00       4505.75       138.303       114.446 
 TP26B              BRICK_P12V0_EN_R_N                BOTTOM        5789.84       4380.00       147.062       111.252 
 TP26B              BRICK_P12V_1_EN_N                 BOTTOM        6056.00       4484.46       153.822       113.905 
 TP26B              BRICK_P12V_EN_R_N                 BOTTOM        4215.94       4383.60       107.085       111.343 
 TP26B              FAN_PWR_R_EN                      BOTTOM        9039.39       2728.64       229.601        69.307 
 TP26B              FM_AC_PWR_CYCLE_BUF               BOTTOM       10955.00       1170.75       278.257        29.737 
 TP26B              FM_AC_PWR_CYCLE_N                 BOTTOM       11314.76       1692.94       287.395        43.001 
 TP26B              FM_AC_PWR_CYCLE_R1_N              BOTTOM       11504.25       1474.01       292.208        37.440 
 TP26B              FM_AC_PWR_CYCLE_R_BUF             BOTTOM       10853.00       1140.16       275.666        28.960 
 TP26B              FM_AC_PWR_CYCLE_R_N               BOTTOM        8430.00       1670.00       214.122        42.418 
 TP26B              FM_U5_VCC                         BOTTOM        9058.19       3028.19       230.078        76.916 
 TP26B              FRU_ADDR1                         BOTTOM        8725.00       3019.06       221.615        76.684 
 TP26B              GPU_HSC_R_EN                      BOTTOM        8790.38       2715.76       223.276        68.980 
 TP26B              NC_U1_READY                       BOTTOM        9455.00       3190.00       240.157        81.026 
 TP26B              NC_U6                             BOTTOM        8335.00       3370.00       211.709        85.598 
 TP26B              P12V_BRICK0_ALERT_N               BOTTOM        5350.00       2959.00       135.890        75.159 
 TP26B              P12V_BRICK1_ALERT_N               BOTTOM        3699.25       2873.57        93.961        72.989 
 TP26B              P12V_BRICK2_ALERT_N               BOTTOM        7985.00       2726.00       202.819        69.240 
 TP26B              P12V_BRICK_PWRGD_N                BOTTOM        8985.00       2856.86       228.219        72.564 
 TP26B              P12V_BRICK_PWRGD_R_N              BOTTOM        8906.76       2726.20       226.232        69.245 
 TP26B              P12V_HPDB_0_ISET                  BOTTOM        1783.29       2329.00        45.296        59.157 
 TP26B              P12V_HPDB_0_ISET_R                BOTTOM        1859.54       2260.83        47.232        57.425 
 TP26B              P3V3_AUX                          BOTTOM        4320.00       4276.00       109.728       108.610 
 TP26B              P3V3_AUX                          BOTTOM        5759.25       4255.00       146.285       108.077 
 TP26B              P3V3_AUX_SCALED                   BOTTOM        9208.99       2728.24       233.908        69.297 
 TP26B              P52V_1_R                          BOTTOM       10243.40       1395.00       260.182        35.433 
 TP26B              P52V_FAN                          BOTTOM        1285.00       4260.00        32.639       108.204 
 TP26B              P52V_HS1_4287_GATE2_RC            BOTTOM       10920.00       3388.00       277.368        86.055 
 TP26B              P52V_HS1_EFAULT                   BOTTOM       10960.00       1650.00       278.384        41.910 
 TP26B              P52V_HS1_EN                       BOTTOM       10635.00       1115.00       270.129        28.321 
 TP26B              P52V_HS1_EN_BUF_DELAY             BOTTOM       10985.00       1569.37       279.019        39.862 
 TP26B              P52V_HS1_EN_DELAY                 BOTTOM       10435.00       1115.00       265.049        28.321 
 TP26B              P52V_HS1_EN_DELAY_N               BOTTOM       11020.00       1480.00       279.908        37.592 
 TP26B              P52V_HS1_ESTART                   BOTTOM       10960.00       1705.00       278.384        43.307 
 TP26B              P52V_HS1_GATE2_R1                 BOTTOM       10955.75       3586.40       278.276        91.095 
 TP26B              P52V_HS1_GATE_R1                  BOTTOM       10955.75       4063.10       278.276       103.203 
 TP26B              P52V_HS1_GATE_RC                  BOTTOM       10911.00       3864.00       277.139        98.146 
 TP26B              P52V_HS1_INTVCC                   BOTTOM       10395.00       1345.00       264.033        34.163 
 TP26B              P52V_HS1_VCAP                     BOTTOM       10955.00       1835.00       278.257        46.609 
 TP26B              PCA9543_MISC_A0                   BOTTOM        7910.00       3620.00       200.914        91.948 
 TP26B              PCA9555_A2                        BOTTOM        8275.00       3185.00       210.185        80.899 
 TP26B              PRSNT_HPDB_N                      BOTTOM        8110.00       2860.00       205.994        72.644 
 TP26B              PU_9543_0_INT0                    BOTTOM        7907.30       3518.39       200.845        89.367 
 TP26B              PU_9543_0_INT1                    BOTTOM        7915.63       3429.17       201.057        87.101 
 TP26B              PU_9543_1_INT0                    BOTTOM        7535.00       3260.00       191.389        82.804 
 TP26B              PU_9543_1_INT1                    BOTTOM        7535.50       3441.61       191.402        87.417 
 TP26B              PU_U4_PIN1                        BOTTOM        8150.00       3185.00       207.010        80.899 
 TP26B              PWRGD_GPU_HSC                     BOTTOM         684.03       3237.00        17.374        82.220 
 TP26B              PWRGD_GPU_HSC_BUF_R               BOTTOM        8710.49       2669.46       221.246        67.804 
 TP26B              PWRGD_GPU_HSC_R                   BOTTOM        8195.00       3365.00       208.153        85.471 
 TP26B              PWRGD_P3V3_AUX_MB                 BOTTOM        9151.43       2886.12       232.446        73.307 
 TP26B              PWRGD_P3V3_AUX_MB_R1              BOTTOM        9145.00       3039.11       232.283        77.193 
 TP26B              PWRGD_P3V3_AUX_MB_R               BOTTOM        9130.78       2715.03       231.922        68.962 
 TP26B              PWRGD_P3V3_HPDB                   BOTTOM        1794.00       3268.00        45.568        83.007 
 TP26B              RST_SMB_PDB_BUF_R1_N              BOTTOM        7754.25       3645.00       196.958        92.583 
 TP26B              RST_SMB_PDB_N                     BOTTOM        9200.00       3201.35       233.680        81.314 
 TP26B              RST_SMB_PDB_R_N                   BOTTOM        9300.86       2729.86       236.242        69.338 
 TP26B              SKU_ID_1                          BOTTOM        8335.00       2810.00       211.709        71.374 
 TP26B              SMB_FRU_CLK                       BOTTOM        8710.00       3480.00       221.234        88.392 
 TP26B              SMB_FRU_DAT                       BOTTOM        8600.00       3480.00       218.440        88.392 
 TP26B              SMB_HPDB_MISC_R_SDA               BOTTOM         697.45       3500.42        17.715        88.911 
 TP26B              SMB_HPDB_MISC_SCL                 BOTTOM        7530.00       3665.00       191.262        93.091 
 TP26B              SMB_HPDB_MISC_SDA                 BOTTOM        7662.40       3664.46       194.625        93.077 
 TP26B              SMB_MB_PDB_R_SCL                  BOTTOM        9452.01       2726.56       240.081        69.255 
 TP26B              SMB_MB_PDB_R_SDA                  BOTTOM        9376.76       2683.56       238.170        68.162 
 TP26B              SMB_MB_PDB_SCL                    BOTTOM        9520.00       2865.00       241.808        72.771 
 TP26B              SMB_P52V_HPDB_R_SCL               BOTTOM         606.00       3355.00        15.392        85.217 
 TP26B              SMB_P52V_HPDB_SCL                 BOTTOM        1632.47       3355.00        41.465        85.217 
 TP26B              SMB_P52V_HPDB_SDA                 BOTTOM        1713.02       3334.71        43.511        84.702 
 TP26B              SMB_P52V_VPDB_SCL                 BOTTOM        3784.79       3141.11        96.134        79.784 
 TP26B              SMB_P52V_VPDB_SCL_R               BOTTOM        7530.20       3385.00       191.267        85.979 
 TP26B              SMB_PDB_MISC_SCL_R                BOTTOM        9425.46       3579.25       239.407        90.913 
 TP26B              SMB_PDB_MISC_SDA_R                BOTTOM        9325.00       3053.85       236.855        77.568 
 TP26B              SMB_VPDB_IOEXP_SCL                BOTTOM        8232.06       2812.07       209.094        71.427 
 TP26B              SMB_VPDB_IOEXP_SDA                BOTTOM        8155.00       2815.00       207.137        71.501 
 TP26B              TP_9543_MISC_INT_N                BOTTOM        7590.00       3655.00       192.786        92.837 
 TP26B              TP_J1_A1                          BOTTOM        8420.75       1589.24       213.887        40.367 
 TP26B              TP_J5_C1                          BOTTOM       12700.00       2900.00       322.580        73.660 
 TP26B              TP_J5_D1                          BOTTOM       12715.00       2820.00       322.961        71.628 
 TP26B              TP_U4_P05                         BOTTOM        8426.00       3176.00       214.020        80.670 
 TP30T              FM_HSC_EN_BUSBAR                  TOP          11210.00        945.00       284.734        24.003 
 TP30T              FM_HSC_EN_FUSE                    TOP          11155.00        975.00       283.337        24.765 
 TP30T              HS1_TMR1                          TOP          10530.00       1365.00       267.462        34.671 
 TP30T              HS1_TMR2                          TOP          10502.20       1265.10       266.756        32.134 
 TP30T              LED_D1_R1                         TOP           8400.00       3630.00       213.360        92.202 
 TP30T              LED_D1_R2                         TOP           8131.00       3686.00       206.527        93.624 
 TP30T              LED_D1_R3                         TOP           8400.00       3455.00       213.360        87.757 
 TP30T              LED_D1_R4                         TOP           8140.50       3414.50       206.769        86.728 
 TP30T              LED_D1_R5                         TOP           8400.00       3375.00       213.360        85.725 
 TP30T              P12V_HPDB                         TOP           1062.30       2879.50        26.982        73.139 
 TP30T              P12V_HPDB                         TOP           1449.00       2245.00        36.805        57.023 
 TP30T              P12V_HPDB                         TOP            777.70       3139.60        19.754        79.746 
 TP30T              P12V_HPDB                         TOP            850.00       3073.10        21.590        78.057 
 TP30T              P12V_HPDB                         TOP            921.10       3009.00        23.396        76.429 
 TP30T              P12V_HPDB                         TOP            998.10       2943.70        25.352        74.770 
 TP30T              P12V_HPDB_0_FLTB                  TOP           1713.74       2519.23        43.529        63.988 
 TP30T              P12V_HPDB_0_IMON                  TOP           1782.65       2477.12        45.279        62.919 
 TP30T              P12V_HPDB_0_PD                    TOP           1416.64       2395.73        35.983        60.852 
 TP30T              P3V3_AND                          TOP          10910.00        890.00       277.114        22.606 
 TP30T              P52V_1                            TOP          11890.00       2485.00       302.006        63.119 
 TP30T              P52V_1                            TOP          11890.00       2660.00       302.006        67.564 
 TP30T              P52V_1                            TOP          11905.00       4025.00       302.387       102.235 
 TP30T              P52V_1                            TOP          11905.00       4200.00       302.387       106.680 
 TP30T              P52V_1                            TOP          12300.00       4580.00       312.420       116.332 
 TP30T              P52V_1                            TOP          12480.00       4580.00       316.992       116.332 
 TP30T              P52V_HS1_CS                       TOP          10660.00       1755.00       270.764        44.577 
 TP30T              P52V_HS1_DVCC                     TOP          10774.00       1413.00       273.660        35.890 
 TP30T              P52V_HS1_DV_DT                    TOP          11587.50       1447.50       294.322        36.767 
 TP30T              P52V_HS1_FB                       TOP          10342.90       1979.90       262.710        50.289 
 TP30T              P52V_HS1_GPO2                     TOP          11180.00       1460.00       283.972        37.084 
 TP30T              P52V_HS1_ISET                     TOP          11051.70       1826.30       280.713        46.388 
 TP30T              P52V_HS1_ISTART                   TOP          11085.00       1760.00       281.559        44.704 
 TP30T              P52V_HS1_MCB                      TOP          11125.00       1510.00       282.575        38.354 
 TP30T              P52V_HS1_RND                      TOP          11109.25       1875.00       282.175        47.625 
 TP30T              P52V_HS1_R_EN                     TOP          10945.00       1030.00       278.003        26.162 
 TP30T              P52V_HS1_SCK                      TOP          10645.00       1660.00       270.383        42.164 
 TP30T              P52V_HS1_TEMPN_R                  TOP          11350.00       2206.00       288.290        56.032 
 TP30T              P52V_HS1_TEMP_R                   TOP          11366.00       2280.60       288.696        57.927 
 TP30T              P52V_HS1_TMR                      TOP          10535.05       1440.80       267.590        36.596 
 TP30T              P52V_HS1_VCC                      TOP          11378.08       1875.88       289.003        47.647 
 TP30T              P52V_HS1_VCP                      TOP          11538.45       1610.98       293.077        40.919 
 TP30T              P52V_HS1_VDSFB                    TOP          10289.40       1821.30       261.351        46.261 
 TP30T              P52V_HS1_VREG                     TOP          11310.88       1869.12       287.296        47.476 
 TP30T              PWRGD_P52V_HS1_PG                 TOP          11271.48       1475.66       286.296        37.482 
 TP30T              SMB_CM_HS1_3V3SB_DATI             TOP          11065.00       1550.00       281.051        39.370 
 TP30T              SMB_CM_HS1_3V3SB_DATO             TOP          11050.00       1475.00       280.670        37.465 
 TP30T              SMB_P52V_HS1_SDAI                 TOP          10595.00       1755.00       269.113        44.577 
 TP30T              SMB_P52V_HS1_SDAO                 TOP          10540.00       1810.00       267.716        45.974 
 TP30T              SMB_P52V_VPDB_SCL_R2              TOP          11055.00       1617.79       280.797        41.092 
 TP30T              SMB_P52V_VPDB_SCL_R3              TOP          10625.00       1810.00       269.875        45.974 
 TP30T              SW_P12V_FILT__P3V3_AUX            TOP           6601.00        399.00       167.665        10.135 
 TP30T              SW_P3V3_AUX_PH                    TOP           7115.00        613.00       180.721        15.570 
 VT20D10B26         GND                               BOTTOM       11144.52       5380.00       283.071       136.652 
 VT20D10B26         GND                               BOTTOM       11144.52       5530.00       283.071       140.462 
 VT20D10B26         GND                               BOTTOM       11236.69       5380.00       285.412       136.652 
 VT20D10B26         GND                               BOTTOM       11236.69       5530.00       285.412       140.462 
 VT20D10B26         GND                               BOTTOM        1835.39       4980.00        46.619       126.492 
 VT20D10B26         GND                               BOTTOM        1835.39       5180.00        46.619       131.572 
 VT20D10B26         GND                               BOTTOM        2315.39       4980.00        58.811       126.492 
 VT20D10B26         GND                               BOTTOM        2315.39       5180.00        58.811       131.572 
 VT20D10B26         GND                               BOTTOM        2460.00       2385.00        62.484        60.579 
 VT20D10B26         GND                               BOTTOM        2795.39       4980.00        71.003       126.492 
 VT20D10B26         GND                               BOTTOM        2795.39       5180.00        71.003       131.572 
 VT20D10B26         GND                               BOTTOM        3410.19       4980.00        86.619       126.492 
 VT20D10B26         GND                               BOTTOM        3410.19       5180.00        86.619       131.572 
 VT20D10B26         GND                               BOTTOM        3890.19       4980.00        98.811       126.492 
 VT20D10B26         GND                               BOTTOM        3890.19       5180.00        98.811       131.572 
 VT20D10B26         GND                               BOTTOM        3985.00       2470.00       101.219        62.738 
 VT20D10B26         GND                               BOTTOM        4020.00       2380.00       102.108        60.452 
 VT20D10B26         GND                               BOTTOM        4370.19       4980.00       111.003       126.492 
 VT20D10B26         GND                               BOTTOM        4370.19       5180.00       111.003       131.572 
 VT20D10B26         GND                               BOTTOM        4985.00       4980.00       126.619       126.492 
 VT20D10B26         GND                               BOTTOM        4985.00       5180.00       126.619       131.572 
 VT20D10B26         GND                               BOTTOM        5465.00       4980.00       138.811       126.492 
 VT20D10B26         GND                               BOTTOM        5465.00       5180.00       138.811       131.572 
 VT20D10B26         GND                               BOTTOM        5945.00       4980.00       151.003       126.492 
 VT20D10B26         GND                               BOTTOM        5945.00       5180.00       151.003       131.572 
 VT20D10B26         GND                               BOTTOM        6479.75        370.00       164.586         9.398 
 VT20D10B26         GND                               BOTTOM        6523.00        568.00       165.684        14.427 
 VT20D10B26         GND                               BOTTOM        6559.81       4980.00       166.619       126.492 
 VT20D10B26         GND                               BOTTOM        6559.81       5180.00       166.619       131.572 
 VT20D10B26         GND                               BOTTOM        6602.00        568.00       167.691        14.427 
 VT20D10B26         GND                               BOTTOM        6681.00        568.00       169.697        14.427 
 VT20D10B26         GND                               BOTTOM        6760.00        568.00       171.704        14.427 
 VT20D10B26         GND                               BOTTOM        6836.00        568.00       173.634        14.427 
 VT20D10B26         GND                               BOTTOM        6845.25        325.00       173.869         8.255 
 VT20D10B26         GND                               BOTTOM        6930.00        566.00       176.022        14.376 
 VT20D10B26         GND                               BOTTOM        7039.81       4980.00       178.811       126.492 
 VT20D10B26         GND                               BOTTOM        7039.81       5180.00       178.811       131.572 
 VT20D10B26         GND                               BOTTOM        7060.00        619.75       179.324        15.742 
 VT20D10B26         GND                               BOTTOM        7519.81       4980.00       191.003       126.492 
 VT20D10B26         GND                               BOTTOM        7519.81       5180.00       191.003       131.572 
 VT20D10B26         GND                               BOTTOM        7615.60        300.00       193.436         7.620 
 VT20D10B26         GND                               BOTTOM        7615.60        385.00       193.436         9.779 
 VT20D10B26         GND                               BOTTOM        7615.60        470.00       193.436        11.938 
 VT20D10B26         GND                               BOTTOM        7615.60        555.00       193.436        14.097 
 VT20D10B26         GND                               BOTTOM        7615.60        640.00       193.436        16.256 
 VT20D10B26         GND_FIELD_SIGNAL                  BOTTOM       10390.16       1890.75       263.910        48.025 
 VT20D10B26         GND_FIELD_SIGNAL                  BOTTOM       11205.24       1384.57       284.613        35.168 
 VT20D10B26         GND_FIELD_SIGNAL                  BOTTOM       11330.00       1980.00       287.782        50.292 
 VT20D10B26         LED_D2_R1                         BOTTOM        7848.55       2651.84       199.353        67.357 
 VT20D10B26         LED_D2_R2                         BOTTOM        7900.00       2596.12       200.660        65.941 
 VT20D10B26         LED_D2_R3                         BOTTOM        7949.00       2659.79       201.905        67.559 
 VT20D10B26         LED_D3_R                          BOTTOM        8060.00       2650.75       204.724        67.329 
 VT20D10B26         P12V_HPDB_0_EN_R                  BOTTOM        1782.65       2134.43        45.279        54.215 
 VT20D10B26         P12V_HPDB_0_FB                    BOTTOM        1600.17       2377.64        40.644        60.392 
 VT20D10B26         P12V_HPDB_0_SS                    BOTTOM        1738.69       2281.68        44.163        57.955 
 VT20D10B26         P12V_HPDB_0_TIMER                 BOTTOM        1759.76       2187.75        44.698        55.569 
 VT20D10B26         P12V_HPDB_PWRGD                   BOTTOM        1660.68       2387.49        42.181        60.642 
 VT20D10B26         P12V_HPDB_PWRGD                   BOTTOM        8530.00       3035.00       216.662        77.089 
 VT20D10B26         P3V3_AUX_CS                       BOTTOM        6900.75        395.00       175.279        10.033 
 VT20D10B26         P3V3_AUX_FB                       BOTTOM        6944.25        295.00       176.384         7.493 
 VT20D10B26         P3V3_AUX_MODE                     BOTTOM        7037.40        541.18       178.750        13.746 
 VT20D10B26         P3V3_AUX_PWRGD                    BOTTOM        7070.00        320.00       179.578         8.128 
 VT20D10B26         P3V3_AUX_REF                      BOTTOM        7037.40        410.00       178.750        10.414 
 VT20D10B26         P52V_1_FUSE_1                     BOTTOM       11775.21       1659.52       299.090        42.152 
 VT20D10B26         P52V_1_FUSE_1                     BOTTOM       11886.00       1660.00       301.904        42.164 
 VT20D10B26         P52V_BUSBAR                       BOTTOM       10920.00        825.00       277.368        20.955 
 VT20D10B26         P52V_HS1_1272_GATE                BOTTOM       11525.00       1865.00       292.735        47.371 
 VT20D10B26         P52V_HS1_4287_GATE2_R             BOTTOM       10220.00       1712.00       259.588        43.485 
 VT20D10B26         P52V_HS1_4287_GATE_R              BOTTOM       10197.00       1666.00       259.004        42.316 
 VT20D10B26         P52V_HS1_ADR0                     BOTTOM       11131.29       1657.19       282.735        42.093 
 VT20D10B26         P52V_HS1_ADR1                     BOTTOM       10493.56       1439.00       266.536        36.551 
 VT20D10B26         P52V_HS1_CLKIN                    BOTTOM       10575.00       1558.77       268.605        39.593 
 VT20D10B26         P52V_HS1_DRAIN_1                  BOTTOM       11351.90       4089.65       288.338       103.877 
 VT20D10B26         P52V_HS1_DRAIN_1                  BOTTOM       11354.04       4572.28       288.393       116.136 
 VT20D10B26         P52V_HS1_DRAIN_1                  BOTTOM       11356.22       4677.32       288.448       118.804 
 VT20D10B26         P52V_HS1_DRAIN_2                  BOTTOM       11352.03       2668.60       288.342        67.782 
 VT20D10B26         P52V_HS1_DRAIN_2                  BOTTOM       11354.03       3143.60       288.392        79.847 
 VT20D10B26         P52V_HS1_DRAIN_2                  BOTTOM       11354.03       3619.79       288.392        91.943 
 VT20D10B26         P52V_HS1_DVCC                     BOTTOM       10439.36       1457.45       265.160        37.019 
 VT20D10B26         P52V_HS1_DVCC                     BOTTOM       10731.54       1408.00       272.581        35.763 
 VT20D10B26         P52V_HS1_DV_DT_R                  BOTTOM       11582.00       1377.00       294.183        34.976 
 VT20D10B26         P52V_HS1_ESTART_R                 BOTTOM       11133.68       1716.19       282.795        43.591 
 VT20D10B26         P52V_HS1_GATE1                    BOTTOM       10678.66       5076.29       271.238       128.938 
 VT20D10B26         P52V_HS1_GATE1_R                  BOTTOM       10616.00       4662.42       269.646       118.425 
 VT20D10B26         P52V_HS1_GATE1_R                  BOTTOM       10616.00       5137.42       269.646       130.490 
 VT20D10B26         P52V_HS1_GATE2                    BOTTOM       10677.30       4603.52       271.203       116.929 
 VT20D10B26         P52V_HS1_GATE2_R                  BOTTOM       10616.00       2762.42       269.646        70.165 
 VT20D10B26         P52V_HS1_GATE2_R                  BOTTOM       10616.00       3237.42       269.646        82.230 
 VT20D10B26         P52V_HS1_GATE3                    BOTTOM       10675.31       4129.42       271.153       104.887 
 VT20D10B26         P52V_HS1_GATE4                    BOTTOM       10677.07       3654.42       271.198        92.822 
 VT20D10B26         P52V_HS1_GATE5                    BOTTOM       10676.79       3179.42       271.190        80.757 
 VT20D10B26         P52V_HS1_GATE6                    BOTTOM       10677.01       2704.42       271.196        68.692 
 VT20D10B26         P52V_HS1_GPO1                     BOTTOM       11212.38       1445.00       284.794        36.703 
 VT20D10B26         P52V_HS1_MODE                     BOTTOM       10545.00       1485.00       267.843        37.719 
 VT20D10B26         P52V_HS1_OV                       BOTTOM       11145.00       1887.00       283.083        47.930 
 VT20D10B26         P52V_HS1_PWRGIN                   BOTTOM       11301.25       1359.40       287.052        34.529 
 VT20D10B26         P52V_HS1_SENSE_N_R1               BOTTOM       11651.90       4712.50       295.958       119.697 
 VT20D10B26         P52V_HS1_SENSE_N_R2               BOTTOM       11650.70       3287.50       295.928        83.503 
 VT20D10B26         P52V_HS1_SENSE_P_R1               BOTTOM       11938.40       4712.50       303.235       119.697 
 VT20D10B26         P52V_HS1_SENSE_P_R2               BOTTOM       11934.11       3287.50       303.126        83.503 
 VT20D10B26         P52V_HS1_SIO                      BOTTOM       10820.00       1436.00       274.828        36.474 
 VT20D10B26         P52V_HS1_TEMP                     BOTTOM       11061.06       2317.41       280.951        58.862 
 VT20D10B26         P52V_HS1_TEMPN                    BOTTOM       11172.90       2242.41       283.792        56.957 
 VT20D10B26         P52V_HS1_TEMPP                    BOTTOM       11172.06       2317.41       283.770        58.862 
 VT20D10B26         P52V_HS1_UVH                      BOTTOM       11235.00       1870.00       285.369        47.498 
 VT20D10B26         P52V_HS1_UVLO_EN                  BOTTOM       10345.00       1450.00       262.763        36.830 
 VT20D10B26         P52V_HS1_VCAP                     BOTTOM       11080.00       1720.00       281.432        43.688 
 VT20D10B26         P52V_HS                           BOTTOM       10166.14       1902.67       258.220        48.328 
 VT20D10B26         P52V_HS                           BOTTOM       10665.00       5380.00       270.891       136.652 
 VT20D10B26         P52V_HS                           BOTTOM       10665.00       5530.00       270.891       140.462 
 VT20D10B26         P52V_HS_1272_S_N                  BOTTOM       11434.90       1835.60       290.446        46.624 
 VT20D10B26         P52V_HS_1272_S_P                  BOTTOM       11795.00       4697.50       299.593       119.317 
 VT20D10B26         P52V_HS_4287_ADC_N                BOTTOM       10221.68       1617.83       259.631        41.093 
 VT20D10B26         P52V_HS_4287_ADC_P                BOTTOM       11795.00       4767.50       299.593       121.095 
 VT20D10B26         P52V_HS_4287_S1N                  BOTTOM       11779.25       4917.34       299.193       124.900 
 VT20D10B26         P52V_HS_4287_S1P                  BOTTOM       10190.40       1573.10       258.836        39.957 
 VT20D10B26         P52V_HS_4287_S2N                  BOTTOM       11778.36       3492.34       299.170        88.705 
 VT20D10B26         P52V_HS_4287_S2P                  BOTTOM       10179.09       1514.24       258.549        38.462 
 VT20D10B26         P52V_HS_FILTER                    BOTTOM        1719.39       4980.00        43.673       126.492 
 VT20D10B26         P52V_HS_FILTER                    BOTTOM        1719.39       5180.00        43.673       131.572 
 VT20D10B26         P52V_HS_FILTER                    BOTTOM        2199.39       4980.00        55.865       126.492 
 VT20D10B26         P52V_HS_FILTER                    BOTTOM        2199.39       5180.00        55.865       131.572 
 VT20D10B26         P52V_HS_FILTER                    BOTTOM        2679.39       4980.00        68.057       126.492 
 VT20D10B26         P52V_HS_FILTER                    BOTTOM        2679.39       5180.00        68.057       131.572 
 VT20D10B26         P52V_HS_FILTER                    BOTTOM        3294.19       4980.00        83.672       126.492 
 VT20D10B26         P52V_HS_FILTER                    BOTTOM        3294.19       5180.00        83.672       131.572 
 VT20D10B26         P52V_HS_FILTER                    BOTTOM        3774.19       4980.00        95.864       126.492 
 VT20D10B26         P52V_HS_FILTER                    BOTTOM        3774.19       5180.00        95.864       131.572 
 VT20D10B26         P52V_HS_FILTER                    BOTTOM        4254.19       4980.00       108.056       126.492 
 VT20D10B26         P52V_HS_FILTER                    BOTTOM        4254.19       5180.00       108.056       131.572 
 VT20D10B26         P52V_HS_FILTER                    BOTTOM        4869.00       4980.00       123.673       126.492 
 VT20D10B26         P52V_HS_FILTER                    BOTTOM        4869.00       5180.00       123.673       131.572 
 VT20D10B26         P52V_HS_FILTER                    BOTTOM        5349.00       4980.00       135.865       126.492 
 VT20D10B26         P52V_HS_FILTER                    BOTTOM        5349.00       5180.00       135.865       131.572 
 VT20D10B26         P52V_HS_FILTER                    BOTTOM        5829.00       4980.00       148.057       126.492 
 VT20D10B26         P52V_HS_FILTER                    BOTTOM        5829.00       5180.00       148.057       131.572 
 VT20D10B26         P52V_HS_FILTER                    BOTTOM        6443.81       4980.00       163.673       126.492 
 VT20D10B26         P52V_HS_FILTER                    BOTTOM        6443.81       5180.00       163.673       131.572 
 VT20D10B26         P52V_HS_FILTER                    BOTTOM        6923.81       4980.00       175.865       126.492 
 VT20D10B26         P52V_HS_FILTER                    BOTTOM        6923.81       5180.00       175.865       131.572 
 VT20D10B26         P52V_HS_FILTER                    BOTTOM        7403.81       4980.00       188.057       126.492 
 VT20D10B26         P52V_HS_FILTER                    BOTTOM        7403.81       5180.00       188.057       131.572 
 VT20D10B26         PWRGD_P52V_HS1_PG_N               BOTTOM       10390.16       1830.27       263.910        46.489 
 VT20D10B26         RST_SMB_PDB_BUF_N                 BOTTOM        9109.92       3610.75       231.392        91.713 
 VT20D10B26         SMB_P52V_HSC_SCL                  BOTTOM       10625.00       1915.00       269.875        48.641 
 VT20D10B26         SMB_P52V_HSC_SDA                  BOTTOM       10945.00       1431.44       278.003        36.359 
 VT20D10B26         SMB_P52V_VPDB_SDA                 BOTTOM        6804.00       3105.00       172.822        78.867 
 VT20D10B26         SMB_PDB_MISC_SDA                  BOTTOM        7540.00       3569.57       191.516        90.667 
 VT20D10B26         SMB_VPDB_MISC_SCL                 BOTTOM        8690.00       3605.00       220.726        91.567 
 VT20D10T30         BOARD_ID_1                        TOP           8535.00       2685.75       216.789        68.218 
 VT20D10T30         FAN_PWR_EN                        TOP           8485.00       3358.00       215.519        85.293 
 VT20D10T30         FAN_PWR_EN_BUF_R                  TOP           8438.43       3543.42       214.336        90.003 
 VT20D10T30         FRU_ADDR0                         TOP           8800.00       3128.55       223.520        79.465 
 VT20D10T30         FRU_ADDR2                         TOP           8700.00       3127.88       220.980        79.448 
 VT20D10T30         FRU_WP_N                          TOP           8750.00       3472.73       222.250        88.207 
 VT20D10T30         MB_MISC_I2C_EN                    TOP           9333.57       3448.43       237.073        87.590 
 VT20D10T30         P12V_BRICK3_ALERT_N               TOP           8365.00       3025.00       212.471        76.835 
 VT20D10T30         P3V3_AUX                          TOP           8700.00       3045.25       220.980        77.349 
 VT20D10T30         P3V3_AUX                          TOP           8800.00       3045.25       223.520        77.349 
 VT20D10T30         P52V_HS1_EFAULT_R                 TOP          11108.00       1700.00       282.143        43.180 
 VT20D10T30         P52V_HS1_FLT                      TOP           8317.50       3182.50       211.265        80.835 
 VT20D10T30         P52V_HS                           TOP           8490.00       3990.00       215.646       101.346 
 VT20D10T30         PCA9543_MISC_A1                   TOP           7920.00       3580.00       201.168        90.932 
 VT20D10T30         PCA9555_A0                        TOP           8276.02       2835.00       210.211        72.009 
 VT20D10T30         PCA9555_A1                        TOP           8195.00       3185.00       208.153        80.899 
 VT20D10T30         PWRGD_GPU_HSC_BUF                 TOP           8270.00       3525.00       210.058        89.535 
 VT20D10T30         PWRGD_P3V3_AUX_MB_BUF             TOP           9331.96       3533.60       237.032        89.753 
 VT20D10T30         PWRGD_P3V3_AUX_MB_BUF_N           TOP           9237.40       3455.00       234.630        87.757 
 VT20D10T30         PWRGD_P3V3_AUX_MB_BUF_R           TOP           9059.41       3203.66       230.109        81.373 
 VT20D10T30         RST_SMB_PDB_BUF_R_N               TOP           9162.60       3550.00       232.730        90.170 
 VT20D10T30         SKU_ID_0                          TOP           8435.00       2685.75       214.249        68.218 
 VT20D10T30         SKU_ID_2                          TOP           8335.00       2685.75       211.709        68.218 
 VT20D10T30         SMB_MB_PDB_SDA                    TOP           9400.00       2838.00       238.760        72.085 
 VT20D10T30         SMB_PDB_MISC_SCL                  TOP           9355.16       3610.75       237.621        91.713 
 VT20D10T30         SMB_VPDB_MISC_SDA                 TOP           8160.00       2705.25       207.264        68.713 
 VT20D10T30         TP_U4_P06                         TOP           8450.00       3030.00       214.630        76.962 
|--------------------------------------------------------------------------------------------------------------------|
|  TOTAL  TESTPIN : 366                                                                                              |
|--------------------------------------------------------------------------------------------------------------------|

===========PADSTACK LIST============
C123D83 => 10
C50D34 => 6
C52D36 => 26
C58D41 => 4
C66D46 => 2
C93D63 => 7
S66D46 => 1
TP26B => 82
TP30T => 52
VT20D10B26 => 149
VT20D10T30 => 27

====================================

=========================Following 11 NETs don't have TEST POINTs=========================
BUS=other (Completed_rate=251 / 262)
GND3
GND_BUSBAR
H24_TP
H25_TP
P3V3_AUX_VCC
SW_P3V3_AUX_BT
SW_P3V3_AUX_BT_R
TDR_SE_50_OHM_BOT
TDR_SE_50_OHM_IN1
TDR_SE_50_OHM_IN2
TDR_SE_50_OHM_TOP

=======================Following Nets has more then one TEST POINTs=======================
GND => 55
GND_FIELD_SIGNAL => 3
P12V_BRICK => 6
P12V_HPDB => 7
P12V_HPDB_PWRGD => 3
P3V3_AUX => 4
P52V_1 => 6
P52V_1_FUSE_1 => 2
P52V_FAN => 3
P52V_HS => 4
P52V_HS1_DRAIN_1 => 3
P52V_HS1_DRAIN_2 => 3
P52V_HS1_DVCC => 3
P52V_HS1_GATE1_R => 2
P52V_HS1_GATE2_R => 2
P52V_HS1_VCAP => 2
P52V_HS_FILTER => 24

==========================================================================================
(1)TOTAL NETs added TESTPOINTs           = 251
(2)TOTAL NETs                            = 262
(3)TOTAL NETs/32 + 40                    = 48.19
(4)TOTAL TESTPOINTs                      = 366
(5)TOTAL TESTPOINTs without NETNAME      = 0
(6)TOTAL NETs added NO_TEST of property  = 5
The coverage for testpoint added on nets = (1)/(2) = 95.80%
Percentage of testable nets tested       = (1)/((2)-(6)) = 97.67%

========================Following TEST POINTs don't have NET NAME=========================

================Following TEST POINTs don't have netname but tied to Pins=================

==========================================================================================
